(kicad_pcb
	(version 20241229)
	(generator "pcbnew")
	(generator_version "9.0")
	(general
		(thickness 1.711)
		(legacy_teardrops no)
	)
	(paper "A4")
	(title_block
		(title "Antmicro Baseboard for Jetson AGX Thor")
		(date "2026-02-18")
		(rev "1.1.0")
		(company "Antmicro Ltd")
		(comment 1 "www.antmicro.com")
		(comment 9 "footprints 593-597 of 1170")
	)
	(layers
		(0 "F.Cu" signal)
		(4 "In1.Cu" signal)
		(6 "In2.Cu" signal)
		(8 "In3.Cu" signal)
		(10 "In4.Cu" jumper)
		(12 "In5.Cu" signal)
		(14 "In6.Cu" signal)
		(16 "In7.Cu" signal)
		(18 "In8.Cu" signal)
		(2 "B.Cu" signal)
		(9 "F.Adhes" user "F.Adhesive")
		(11 "B.Adhes" user "B.Adhesive")
		(13 "F.Paste" user)
		(15 "B.Paste" user)
		(5 "F.SilkS" user "F.Silkscreen")
		(7 "B.SilkS" user "B.Silkscreen")
		(1 "F.Mask" user)
		(3 "B.Mask" user)
		(17 "Dwgs.User" user "User.Drawings")
		(19 "Cmts.User" user "User.Comments")
		(21 "Eco1.User" user "User.Eco1")
		(23 "Eco2.User" user "User.Eco2")
		(25 "Edge.Cuts" user)
		(27 "Margin" user)
		(31 "F.CrtYd" user "F.Courtyard")
		(29 "B.CrtYd" user "B.Courtyard")
		(35 "F.Fab" user)
		(33 "B.Fab" user)
	)
	(footprint "antmicro-footprints:R_0402_1005Metric"
		(layer "F.Cu")
		(at 212.8 95.4 -90)
		(descr "Resistor SMD 0402")
		(tags "resistor SMD 0402")
		(property "Reference" "R117"
			(at -1.63 -1.62 90)
			(layer "F.SilkS")
			(effects
				(font
					(size 0.7 0.7)
					(thickness 0.15)
				)
				(justify right top)
			)
		)
		(property "Value" "R_100k_0402"
			(at -1.011843 1.772047 90)
			(layer "F.Fab")
			(effects
				(font
					(size 0.7 0.7)
					(thickness 0.15)
				)
				(justify right top)
			)
		)
		(property "Datasheet" "https://www.bourns.com/docs/product-datasheets/cr.pdf"
			(at 0 0 90)
			(layer "F.Fab")
			(hide yes)
			(effects
				(font
					(size 1.27 1.27)
					(thickness 0.15)
				)
			)
		)
		(property "Description" "SMD Chip Resistor, 100 kohm, ± 1%, 62.5 mW, 0402 [1005 Metric], Thick Film, General Purpose"
			(at 0 0 90)
			(layer "F.Fab")
			(hide yes)
			(effects
				(font
					(size 1.27 1.27)
					(thickness 0.15)
				)
			)
		)
		(property "Manufacturer" "Bourns"
			(at 0 0 270)
			(unlocked yes)
			(layer "F.Fab")
			(hide yes)
			(effects
				(font
					(size 1 1)
					(thickness 0.15)
				)
			)
		)
		(property "MPN" "CR0402-FX-1003GLF"
			(at 0 0 270)
			(unlocked yes)
			(layer "F.Fab")
			(hide yes)
			(effects
				(font
					(size 1 1)
					(thickness 0.15)
				)
			)
		)
		(property "Val" "100k"
			(at 0 0 270)
			(unlocked yes)
			(layer "F.Fab")
			(hide yes)
			(effects
				(font
					(size 1 1)
					(thickness 0.15)
				)
			)
		)
		(property "License" "Apache-2.0"
			(at 0 0 270)
			(unlocked yes)
			(layer "F.Fab")
			(hide yes)
			(effects
				(font
					(size 1 1)
					(thickness 0.15)
				)
			)
		)
		(property "Author" "Antmicro"
			(at 0 0 270)
			(unlocked yes)
			(layer "F.Fab")
			(hide yes)
			(effects
				(font
					(size 1 1)
					(thickness 0.15)
				)
			)
		)
		(property "Tolerance" "1%"
			(at 0 0 270)
			(unlocked yes)
			(layer "F.Fab")
			(hide yes)
			(effects
				(font
					(size 1 1)
					(thickness 0.15)
				)
			)
		)
		(sheetname "/USB DP Alt mode/")
		(sheetfile "usb_dp.kicad_sch")
		(attr smd)
		(fp_rect
			(start -0.925 -0.47)
			(end 0.925 0.47)
			(stroke
				(width 0.05)
				(type default)
			)
			(fill no)
			(layer "F.CrtYd")
		)
		(fp_rect
			(start -0.5 -0.25)
			(end 0.5 0.25)
			(stroke
				(width 0.15)
				(type solid)
			)
			(fill no)
			(layer "F.Fab")
		)
		(fp_text user "Author: Antmicro"
			(at -0.95 4.169 90)
			(layer "F.Fab")
			(effects
				(font
					(size 0.7 0.7)
					(thickness 0.15)
				)
				(justify right top)
			)
		)
		(fp_text user "${REFERENCE}"
			(at -0.95 3.168 90)
			(layer "F.Fab")
			(effects
				(font
					(size 0.7 0.7)
					(thickness 0.15)
				)
				(justify right top)
			)
		)
		(fp_text user "License: Apache-2.0"
			(at -0.95 5.169 90)
			(layer "F.Fab")
			(effects
				(font
					(size 0.7 0.7)
					(thickness 0.15)
				)
				(justify right top)
			)
		)
		(pad "1" smd roundrect
			(at -0.48 0 270)
			(size 0.59 0.64)
			(layers "F.Cu" "F.Mask" "F.Paste")
			(roundrect_rratio 0.25)
			(net 635 "/SoM_IO2/DP0.AUX+")
			(pintype "passive")
		)
		(pad "2" smd roundrect
			(at 0.48 0 270)
			(size 0.59 0.64)
			(layers "F.Cu" "F.Mask" "F.Paste")
			(roundrect_rratio 0.25)
			(net 1 "GND")
			(pintype "passive")
		)
	)
	(footprint "antmicro-footprints:TP_SMD_0.75mm"
		(layer "F.Cu")
		(at 73.2 127.2)
		(property "Reference" "TP112"
			(at -0.35 -4.000001 270)
			(layer "F.SilkS")
			(effects
				(font
					(size 0.7 0.7)
					(thickness 0.15)
				)
				(justify right top)
			)
		)
		(property "Value" "TP_0.75mm_SMD"
			(at 0 1.2 180)
			(layer "F.Fab")
			(effects
				(font
					(size 0.7 0.7)
					(thickness 0.15)
				)
				(justify right top)
			)
		)
		(property "Description" "SMT test point"
			(at 0 0 180)
			(layer "F.Fab")
			(hide yes)
			(effects
				(font
					(size 1.27 1.27)
					(thickness 0.15)
				)
			)
		)
		(property "MPN" ""
			(at 0 0 0)
			(unlocked yes)
			(layer "F.Fab")
			(hide yes)
			(effects
				(font
					(size 1 1)
					(thickness 0.15)
				)
			)
		)
		(property "Manufacturer" ""
			(at 0 0 0)
			(unlocked yes)
			(layer "F.Fab")
			(hide yes)
			(effects
				(font
					(size 1 1)
					(thickness 0.15)
				)
			)
		)
		(property "Author" "Antmicro"
			(at 0 0 0)
			(unlocked yes)
			(layer "F.Fab")
			(hide yes)
			(effects
				(font
					(size 1 1)
					(thickness 0.15)
				)
			)
		)
		(property "License" "Apache-2.0"
			(at 0 0 0)
			(unlocked yes)
			(layer "F.Fab")
			(hide yes)
			(effects
				(font
					(size 1 1)
					(thickness 0.15)
				)
			)
		)
		(sheetname "/Expansion connector/")
		(sheetfile "expansion_connector.kicad_sch")
		(attr exclude_from_pos_files exclude_from_bom)
		(fp_circle
			(center 0 0)
			(end 0.475 0)
			(stroke
				(width 0.05)
				(type default)
			)
			(fill no)
			(layer "F.CrtYd")
		)
		(fp_text user "${REFERENCE}"
			(at -0.4 2.7 180)
			(layer "F.Fab")
			(effects
				(font
					(size 0.7 0.7)
					(thickness 0.15)
				)
				(justify right top)
			)
		)
		(fp_text user "Author: Antmicro"
			(at -0.4 3.901 180)
			(layer "F.Fab")
			(effects
				(font
					(size 0.7 0.7)
					(thickness 0.15)
				)
				(justify right top)
			)
		)
		(fp_text user "License: Apache-2.0"
			(at -0.4 5.101 180)
			(layer "F.Fab")
			(effects
				(font
					(size 0.7 0.7)
					(thickness 0.15)
				)
				(justify right top)
			)
		)
		(pad "1" smd circle
			(at 0 0)
			(size 0.75 0.75)
			(layers "F.Cu" "F.Mask")
			(net 450 "Net-(J18-PadJ39)")
			(pinfunction "1")
			(pintype "passive")
		)
	)
	(footprint "antmicro-footprints:C_0805_2012Metric"
		(layer "F.Cu")
		(at 169.52 89.1 90)
		(descr "Capacitor SMD 0805")
		(tags "capacitor SMD 0805")
		(property "Reference" "C275"
			(at -1.67 -3.93 90)
			(layer "F.SilkS")
			(effects
				(font
					(size 0.7 0.7)
					(thickness 0.15)
				)
				(justify left bottom)
			)
		)
		(property "Value" "C_22u_25V_0805"
			(at -2.055717 1.963152 90)
			(layer "F.Fab")
			(effects
				(font
					(size 0.7 0.7)
					(thickness 0.15)
				)
				(justify left bottom)
			)
		)
		(property "Datasheet" "https://product.samsungsem.com/mlcc/CL21A226MAYNNN.do"
			(at 0 0 90)
			(layer "F.Fab")
			(hide yes)
			(effects
				(font
					(size 1.27 1.27)
					(thickness 0.15)
				)
			)
		)
		(property "Description" "SMT Multilayer Ceramic Capacitor, 22uF, +/-20%, 25V, X5R, 0805 [2012 Metric]"
			(at 0 0 90)
			(layer "F.Fab")
			(hide yes)
			(effects
				(font
					(size 1.27 1.27)
					(thickness 0.15)
				)
			)
		)
		(property "MPN" "CL21A226MAYNNNE"
			(at 0 0 90)
			(unlocked yes)
			(layer "F.Fab")
			(hide yes)
			(effects
				(font
					(size 1 1)
					(thickness 0.15)
				)
			)
		)
		(property "Manufacturer" "Samsung Electro-Mechanics"
			(at 0 0 90)
			(unlocked yes)
			(layer "F.Fab")
			(hide yes)
			(effects
				(font
					(size 1 1)
					(thickness 0.15)
				)
			)
		)
		(property "License" "Apache-2.0"
			(at 0 0 90)
			(unlocked yes)
			(layer "F.Fab")
			(hide yes)
			(effects
				(font
					(size 1 1)
					(thickness 0.15)
				)
			)
		)
		(property "Author" "Antmicro"
			(at 0 0 90)
			(unlocked yes)
			(layer "F.Fab")
			(hide yes)
			(effects
				(font
					(size 1 1)
					(thickness 0.15)
				)
			)
		)
		(property "Val" "22u"
			(at 0 0 90)
			(unlocked yes)
			(layer "F.Fab")
			(hide yes)
			(effects
				(font
					(size 1 1)
					(thickness 0.15)
				)
			)
		)
		(property "Voltage" "25V"
			(at 0 0 90)
			(unlocked yes)
			(layer "F.Fab")
			(hide yes)
			(effects
				(font
					(size 1 1)
					(thickness 0.15)
				)
			)
		)
		(property "Dielectric" "X5R"
			(at 0 0 90)
			(unlocked yes)
			(layer "F.Fab")
			(hide yes)
			(effects
				(font
					(size 1 1)
					(thickness 0.15)
				)
			)
		)
		(property "Public" "False"
			(at 0 0 90)
			(unlocked yes)
			(layer "F.Fab")
			(hide yes)
			(effects
				(font
					(size 1 1)
					(thickness 0.15)
				)
			)
		)
		(component_classes
			(class "DCDC_SOM")
		)
		(sheetname "/DCDC/")
		(sheetfile "dcdc.kicad_sch")
		(attr smd)
		(fp_line
			(start -0.3 -0.7)
			(end 0.3 -0.7)
			(stroke
				(width 0.15)
				(type solid)
			)
			(layer "F.SilkS")
		)
		(fp_line
			(start -0.3 0.7)
			(end 0.3 0.7)
			(stroke
				(width 0.15)
				(type solid)
			)
			(layer "F.SilkS")
		)
		(fp_rect
			(start 1.95 -0.9)
			(end -1.95 0.9)
			(stroke
				(width 0.05)
				(type default)
			)
			(fill no)
			(layer "F.CrtYd")
		)
		(fp_rect
			(start -0.95 -0.675)
			(end 0.95 0.675)
			(stroke
				(width 0.15)
				(type solid)
			)
			(fill no)
			(layer "F.Fab")
		)
		(fp_text user "License: Apache-2.0"
			(at -1.9 4.947 90)
			(layer "F.Fab")
			(effects
				(font
					(size 0.7 0.7)
					(thickness 0.15)
				)
				(justify left bottom)
			)
		)
		(fp_text user "${REFERENCE}"
			(at -1.9 3.947 90)
			(layer "F.Fab")
			(effects
				(font
					(size 0.7 0.7)
					(thickness 0.15)
				)
				(justify left bottom)
			)
		)
		(fp_text user "Author: Antmicro"
			(at -1.9 5.947 90)
			(layer "F.Fab")
			(effects
				(font
					(size 0.7 0.7)
					(thickness 0.15)
				)
				(justify left bottom)
			)
		)
		(pad "1" smd roundrect
			(at -1.1 0 90)
			(size 1.2 1.3)
			(layers "F.Cu" "F.Mask" "F.Paste")
			(roundrect_rratio 0.25)
			(net 1 "GND")
			(pintype "passive")
		)
		(pad "2" smd roundrect
			(at 1.1 0 90)
			(size 1.2 1.3)
			(layers "F.Cu" "F.Mask" "F.Paste")
			(roundrect_rratio 0.25)
			(net 13 "VCC")
			(pintype "passive")
		)
	)
	(footprint "antmicro-footprints:SW_KMR211NGLFS_SMD"
		(layer "F.Cu")
		(at 191 55.52 180)
		(property "Reference" "S2"
			(at 1.4 -2.08 180)
			(layer "F.SilkS")
			(hide yes)
			(effects
				(font
					(size 0.7 0.7)
					(thickness 0.15)
				)
				(justify right top)
			)
		)
		(property "Value" "SW_KMR211NGLFS_SMD"
			(at 0 2.8 0)
			(layer "F.Fab")
			(effects
				(font
					(size 0.7 0.7)
					(thickness 0.15)
				)
				(justify right top)
			)
		)
		(property "Datasheet" "http://www.farnell.com/datasheets/2631211.pdf"
			(at 0 0 0)
			(layer "F.Fab")
			(hide yes)
			(effects
				(font
					(size 1.27 1.27)
					(thickness 0.15)
				)
			)
		)
		(property "Description" "Tactile Switch, KMR 2 Series, Top Actuated, Surface Mount, Oval Button, 120 gf, 50mA at 32VDC"
			(at 0 0 0)
			(layer "F.Fab")
			(hide yes)
			(effects
				(font
					(size 1.27 1.27)
					(thickness 0.15)
				)
			)
		)
		(property "MPN" "KMR211NGLFS"
			(at 0 0 180)
			(unlocked yes)
			(layer "F.Fab")
			(hide yes)
			(effects
				(font
					(size 1 1)
					(thickness 0.15)
				)
			)
		)
		(property "Manufacturer" "C&K"
			(at 0 0 180)
			(unlocked yes)
			(layer "F.Fab")
			(hide yes)
			(effects
				(font
					(size 1 1)
					(thickness 0.15)
				)
			)
		)
		(property "Author" "Antmicro"
			(at 0 0 180)
			(unlocked yes)
			(layer "F.Fab")
			(hide yes)
			(effects
				(font
					(size 1 1)
					(thickness 0.15)
				)
			)
		)
		(property "License" "Apache-2.0"
			(at 0 0 180)
			(unlocked yes)
			(layer "F.Fab")
			(hide yes)
			(effects
				(font
					(size 1 1)
					(thickness 0.15)
				)
			)
		)
		(sheetname "/Peripherals/")
		(sheetfile "peripherals.kicad_sch")
		(attr smd)
		(fp_line
			(start 2.101 1.601)
			(end 2.101 1.48)
			(stroke
				(width 0.15)
				(type solid)
			)
			(layer "F.SilkS")
		)
		(fp_line
			(start 2.101 1.601)
			(end -2.1 1.601)
			(stroke
				(width 0.15)
				(type solid)
			)
			(layer "F.SilkS")
		)
		(fp_line
			(start 2.101 -1.58)
			(end 2.101 -1.459)
			(stroke
				(width 0.15)
				(type solid)
			)
			(layer "F.SilkS")
		)
		(fp_line
			(start 2.101 -1.6)
			(end -2.1 -1.6)
			(stroke
				(width 0.15)
				(type solid)
			)
			(layer "F.SilkS")
		)
		(fp_line
			(start -2.1 1.601)
			(end -2.1 1.48)
			(stroke
				(width 0.15)
				(type solid)
			)
			(layer "F.SilkS")
		)
		(fp_line
			(start -2.1 -1.6)
			(end -2.1 -1.499)
			(stroke
				(width 0.15)
				(type solid)
			)
			(layer "F.SilkS")
		)
		(fp_poly
			(pts
				(xy 2.751 1.75) (xy 2.751 -1.749) (xy -2.748 -1.749) (xy -2.748 1.749999)
			)
			(stroke
				(width 0.05)
				(type solid)
			)
			(fill no)
			(layer "F.CrtYd")
		)
		(fp_line
			(start 2.101 1.601)
			(end 2.101 -1.6)
			(stroke
				(width 0.15)
				(type solid)
			)
			(layer "F.Fab")
		)
		(fp_line
			(start 2.101 -1.6)
			(end -2.1 -1.6)
			(stroke
				(width 0.15)
				(type solid)
			)
			(layer "F.Fab")
		)
		(fp_line
			(start 0.25 0.802)
			(end -0.248 0.802)
			(stroke
				(width 0.15)
				(type solid)
			)
			(layer "F.Fab")
		)
		(fp_line
			(start -0.248 -0.8)
			(end 0.25 -0.8)
			(stroke
				(width 0.15)
				(type solid)
			)
			(layer "F.Fab")
		)
		(fp_line
			(start -2.1 1.601)
			(end 2.101 1.601)
			(stroke
				(width 0.15)
				(type solid)
			)
			(layer "F.Fab")
		)
		(fp_line
			(start -2.1 -1.6)
			(end -2.1 1.601)
			(stroke
				(width 0.15)
				(type solid)
			)
			(layer "F.Fab")
		)
		(fp_arc
			(start 0.25 -0.8)
			(mid 1.051001 0.001)
			(end 0.25 0.802)
			(stroke
				(width 0.15)
				(type solid)
			)
			(layer "F.Fab")
		)
		(fp_arc
			(start -0.248 0.802)
			(mid -1.050001 0.001)
			(end -0.248 -0.8)
			(stroke
				(width 0.15)
				(type solid)
			)
			(layer "F.Fab")
		)
		(fp_text user "${REFERENCE}"
			(at -3 4.25 0)
			(layer "F.Fab")
			(effects
				(font
					(size 0.7 0.7)
					(thickness 0.15)
				)
				(justify right top)
			)
		)
		(fp_text user "License: Apache-2.0"
			(at -3 6.75 0)
			(layer "F.Fab")
			(effects
				(font
					(size 0.7 0.7)
					(thickness 0.15)
				)
				(justify right top)
			)
		)
		(fp_text user "Author: Antmicro"
			(at -3 5.5 0)
			(layer "F.Fab")
			(effects
				(font
					(size 0.7 0.7)
					(thickness 0.15)
				)
				(justify right top)
			)
		)
		(pad "1" smd rect
			(at -2.048 -0.8)
			(size 0.9 1)
			(layers "F.Cu" "F.Mask" "F.Paste")
			(net 448 "/Expansion connector/GPIO.USER_BTN0")
			(pinfunction "1")
			(pintype "passive")
		)
		(pad "2" smd rect
			(at 2.049999 -0.8)
			(size 0.9 1)
			(layers "F.Cu" "F.Mask" "F.Paste")
			(net 448 "/Expansion connector/GPIO.USER_BTN0")
			(pinfunction "2")
			(pintype "passive")
		)
		(pad "3" smd rect
			(at -2.048 0.802)
			(size 0.9 1)
			(layers "F.Cu" "F.Mask" "F.Paste")
			(net 1 "GND")
			(pinfunction "3")
			(pintype "passive")
		)
		(pad "4" smd rect
			(at 2.05 0.802001)
			(size 0.9 1)
			(layers "F.Cu" "F.Mask" "F.Paste")
			(net 1 "GND")
			(pinfunction "4")
			(pintype "passive")
		)
	)
	(footprint "antmicro-footprints:C_0402_1005Metric"
		(layer "F.Cu")
		(at 197.215 125.3)
		(descr "Capacitor SMD 0402")
		(tags "capacitor SMD 0402")
		(property "Reference" "C98"
			(at -1.015 1.4 0)
			(layer "F.SilkS")
			(effects
				(font
					(size 0.7 0.7)
					(thickness 0.15)
				)
				(justify left bottom)
			)
		)
		(property "Value" "C_100n_0402"
			(at -1.022927 2.155213 0)
			(layer "F.Fab")
			(effects
				(font
					(size 0.7 0.7)
					(thickness 0.15)
				)
				(justify left bottom)
			)
		)
		(property "Datasheet" "https://www.murata.com/products/productdetail?partno=GRM155R61H104KE14%23"
			(at 0 0 0)
			(layer "F.Fab")
			(hide yes)
			(effects
				(font
					(size 1.27 1.27)
					(thickness 0.15)
				)
			)
		)
		(property "Description" "SMD Multilayer Ceramic Capacitor, 0.1 µF, 50 V, 0402 [1005 Metric], ± 10%, X5R, GRM Series"
			(at 0 0 0)
			(layer "F.Fab")
			(hide yes)
			(effects
				(font
					(size 1.27 1.27)
					(thickness 0.15)
				)
			)
		)
		(property "MPN" "GRM155R61H104KE14D"
			(at 0 0 0)
			(unlocked yes)
			(layer "F.Fab")
			(hide yes)
			(effects
				(font
					(size 1 1)
					(thickness 0.15)
				)
			)
		)
		(property "Val" "100n"
			(at 0 0 0)
			(unlocked yes)
			(layer "F.Fab")
			(hide yes)
			(effects
				(font
					(size 1 1)
					(thickness 0.15)
				)
			)
		)
		(property "Voltage" "50V"
			(at 0 0 0)
			(unlocked yes)
			(layer "F.Fab")
			(hide yes)
			(effects
				(font
					(size 1 1)
					(thickness 0.15)
				)
			)
		)
		(property "Dielectric" "X5R"
			(at 0 0 0)
			(unlocked yes)
			(layer "F.Fab")
			(hide yes)
			(effects
				(font
					(size 1 1)
					(thickness 0.15)
				)
			)
		)
		(property "Manufacturer" "Murata"
			(at 0 0 0)
			(unlocked yes)
			(layer "F.Fab")
			(hide yes)
			(effects
				(font
					(size 1 1)
					(thickness 0.15)
				)
			)
		)
		(property "License" "Apache-2.0"
			(at 0 0 0)
			(unlocked yes)
			(layer "F.Fab")
			(hide yes)
			(effects
				(font
					(size 1 1)
					(thickness 0.15)
				)
			)
		)
		(property "Author" "Antmicro"
			(at 0 0 0)
			(unlocked yes)
			(layer "F.Fab")
			(hide yes)
			(effects
				(font
					(size 1 1)
					(thickness 0.15)
				)
			)
		)
		(sheetname "/USB Hub/")
		(sheetfile "usb_hub.kicad_sch")
		(attr smd)
		(fp_rect
			(start -0.925 -0.47)
			(end 0.925 0.47)
			(stroke
				(width 0.05)
				(type default)
			)
			(fill no)
			(layer "F.CrtYd")
		)
		(fp_line
			(start -0.494 -0.25)
			(end 0.504 -0.25)
			(stroke
				(width 0.15)
				(type solid)
			)
			(layer "F.Fab")
		)
		(fp_line
			(start -0.494 0.248)
			(end -0.494 -0.25)
			(stroke
				(width 0.15)
				(type solid)
			)
			(layer "F.Fab")
		)
		(fp_line
			(start 0.504 -0.25)
			(end 0.504 0.248)
			(stroke
				(width 0.15)
				(type solid)
			)
			(layer "F.Fab")
		)
		(fp_line
			(start 0.504 0.248)
			(end -0.494 0.248)
			(stroke
				(width 0.15)
				(type solid)
			)
			(layer "F.Fab")
		)
		(fp_text user "${REFERENCE}"
			(at -0.939 4.599 0)
			(layer "F.Fab")
			(effects
				(font
					(size 0.7 0.7)
					(thickness 0.15)
				)
				(justify left bottom)
			)
		)
		(fp_text user "Author: Antmicro"
			(at -0.939 3.399 0)
			(layer "F.Fab")
			(effects
				(font
					(size 0.7 0.7)
					(thickness 0.15)
				)
				(justify left bottom)
			)
		)
		(fp_text user "License: Apache-2.0"
			(at -0.939 5.799 0)
			(layer "F.Fab")
			(effects
				(font
					(size 0.7 0.7)
					(thickness 0.15)
				)
				(justify left bottom)
			)
		)
		(pad "1" smd roundrect
			(at -0.48 0)
			(size 0.59 0.64)
			(layers "F.Cu" "F.Mask" "F.Paste")
			(roundrect_rratio 0.25)
			(net 1 "GND")
			(pintype "passive")
		)
		(pad "2" smd roundrect
			(at 0.48 0)
			(size 0.59 0.64)
			(layers "F.Cu" "F.Mask" "F.Paste")
			(roundrect_rratio 0.25)
			(net 2 "+3V3")
			(pintype "passive")
		)
	)
)
